(kicad_pcb
	(version 20260206)
	(generator "pcbnew")
	(generator_version "10.0")
	(general
		(thickness 1.6)
		(legacy_teardrops no)
	)
	(paper "A4")
	(title_block
		(title "9054_F0T_PDB_BD_GPU_F_V04_1213_1550_OCP.brd")
		(comment 1 "Grand Teton / footprints 515-520 of 608")
	)
	(layers
		(0 "F.Cu" signal "TOP")
		(4 "In1.Cu" signal "GND")
		(6 "In2.Cu" signal "IN1")
		(8 "In3.Cu" signal "GND1")
		(10 "In4.Cu" signal "VCC")
		(12 "In5.Cu" signal "VCC1")
		(14 "In6.Cu" signal "GND2")
		(16 "In7.Cu" signal "IN2")
		(18 "In8.Cu" signal "GND3")
		(2 "B.Cu" signal "BOTTOM")
		(9 "F.Adhes" user "F.Adhesive")
		(11 "B.Adhes" user "B.Adhesive")
		(13 "F.Paste" user "Package Geometry/Pastemask Top")
		(15 "B.Paste" user "Package Geometry/Pastemask Bottom")
		(5 "F.SilkS" user "Ref Des/Silkscreen Top")
		(7 "B.SilkS" user "Ref Des/Silkscreen Bottom")
		(1 "F.Mask" user "Board Geometry/Soldermask Top")
		(3 "B.Mask" user "Board Geometry/Soldermask Bottom")
		(17 "Dwgs.User" user "User.Drawings")
		(19 "Cmts.User" user "User.Comments")
		(21 "Eco1.User" user "User.Eco1")
		(23 "Eco2.User" user "User.Eco2")
		(25 "Edge.Cuts" user "Board Geometry/Outline")
		(27 "Margin" user)
		(31 "F.CrtYd" user "Package Geometry/Place Bound Top")
		(29 "B.CrtYd" user "Package Geometry/Place Bound Bottom")
		(35 "F.Fab" user "Ref Des/Assembly Top")
		(33 "B.Fab" user "Ref Des/Assembly Bottom")
	)
	(footprint ""
		(layer "B.Cu")
		(at 270.0274 -62.357)
		(property "Reference" "PR6932"
			(at 0 0 0)
			(layer "B.SilkS")
			(hide yes)
			(effects
				(font
					(size 1.27 1.27)
				)
				(justify mirror)
			)
		)
		(property "Value" ""
			(at 0 0 0)
			(layer "B.Fab")
			(effects
				(font
					(size 1.27 1.27)
				)
				(justify mirror)
			)
		)
		(duplicate_pad_numbers_are_jumpers no)
		(fp_line
			(start -0.7874 -0.4064)
			(end -0.7874 0.4064)
			(stroke
				(width 0.1524)
				(type default)
			)
			(layer "B.SilkS")
		)
		(fp_line
			(start -0.7874 0.4064)
			(end 0.7874 0.4064)
			(stroke
				(width 0.1524)
				(type default)
			)
			(layer "B.SilkS")
		)
		(fp_line
			(start 0.7874 -0.4064)
			(end -0.7874 -0.4064)
			(stroke
				(width 0.1524)
				(type default)
			)
			(layer "B.SilkS")
		)
		(fp_line
			(start 0.7874 0.4064)
			(end 0.7874 -0.4064)
			(stroke
				(width 0.1524)
				(type default)
			)
			(layer "B.SilkS")
		)
		(fp_line
			(start -0.67945 -0.3048)
			(end -0.67945 0.3048)
			(stroke
				(width 0.1)
				(type default)
			)
			(layer "B.Fab")
		)
		(fp_line
			(start -0.67945 0.3048)
			(end -0.120396 0.3048)
			(stroke
				(width 0.1)
				(type default)
			)
			(layer "B.Fab")
		)
		(fp_line
			(start -0.12065 -0.3048)
			(end -0.67945 -0.3048)
			(stroke
				(width 0.1)
				(type default)
			)
			(layer "B.Fab")
		)
		(fp_line
			(start -0.12065 -0.2794)
			(end -0.12065 -0.3048)
			(stroke
				(width 0.1)
				(type default)
			)
			(layer "B.Fab")
		)
		(fp_line
			(start -0.120396 0.2794)
			(end 0.12065 0.2794)
			(stroke
				(width 0.1)
				(type default)
			)
			(layer "B.Fab")
		)
		(fp_line
			(start -0.120396 0.3048)
			(end -0.120396 0.2794)
			(stroke
				(width 0.1)
				(type default)
			)
			(layer "B.Fab")
		)
		(fp_line
			(start 0.12065 -0.305054)
			(end 0.12065 -0.2794)
			(stroke
				(width 0.1)
				(type default)
			)
			(layer "B.Fab")
		)
		(fp_line
			(start 0.12065 -0.2794)
			(end -0.12065 -0.2794)
			(stroke
				(width 0.1)
				(type default)
			)
			(layer "B.Fab")
		)
		(fp_line
			(start 0.12065 0.2794)
			(end 0.12065 0.3048)
			(stroke
				(width 0.1)
				(type default)
			)
			(layer "B.Fab")
		)
		(fp_line
			(start 0.12065 0.3048)
			(end 0.67945 0.3048)
			(stroke
				(width 0.1)
				(type default)
			)
			(layer "B.Fab")
		)
		(fp_line
			(start 0.67945 -0.305054)
			(end 0.12065 -0.305054)
			(stroke
				(width 0.1)
				(type default)
			)
			(layer "B.Fab")
		)
		(fp_line
			(start 0.67945 0.3048)
			(end 0.67945 -0.305054)
			(stroke
				(width 0.1)
				(type default)
			)
			(layer "B.Fab")
		)
		(pad "1" smd circle
			(at 0.40005 0 180)
			(size 0 0)
			(layers "B.Cu" "B.Mask" "B.Paste")
			(net "P52V_HS1_PWRGIN")
		)
		(pad "2" smd circle
			(at -0.40005 0 180)
			(size 0 0)
			(layers "B.Cu" "B.Mask" "B.Paste")
			(net "GND_FIELD_SIGNAL")
		)
	)
	(footprint ""
		(layer "B.Cu")
		(at 152.573736 -79.375 180)
		(property "Reference" "PC595"
			(at 0 0 0)
			(layer "B.SilkS")
			(hide yes)
			(effects
				(font
					(size 1.27 1.27)
				)
				(justify mirror)
			)
		)
		(property "Value" ""
			(at 0 0 0)
			(layer "B.Fab")
			(effects
				(font
					(size 1.27 1.27)
				)
				(justify mirror)
			)
		)
		(duplicate_pad_numbers_are_jumpers no)
		(fp_line
			(start 2.2098 0.9398)
			(end 2.2098 -0.9398)
			(stroke
				(width 0.1524)
				(type default)
			)
			(layer "B.SilkS")
		)
		(fp_line
			(start 2.2098 -0.9398)
			(end -2.2098 -0.9398)
			(stroke
				(width 0.1524)
				(type default)
			)
			(layer "B.SilkS")
		)
		(fp_line
			(start -2.2098 0.9398)
			(end 2.2098 0.9398)
			(stroke
				(width 0.1524)
				(type default)
			)
			(layer "B.SilkS")
		)
		(fp_line
			(start -2.2098 -0.9398)
			(end -2.2098 0.9398)
			(stroke
				(width 0.1524)
				(type default)
			)
			(layer "B.SilkS")
		)
		(fp_line
			(start 2.1082 0.8382)
			(end 2.1082 -0.8382)
			(stroke
				(width 0.1)
				(type default)
			)
			(layer "B.Fab")
		)
		(fp_line
			(start 2.1082 -0.8382)
			(end 1.6764 -0.8382)
			(stroke
				(width 0.1)
				(type default)
			)
			(layer "B.Fab")
		)
		(fp_line
			(start 1.6764 0.9398)
			(end 1.6764 0.889)
			(stroke
				(width 0.1)
				(type default)
			)
			(layer "B.Fab")
		)
		(fp_line
			(start 1.6764 0.889)
			(end 1.6764 0.8382)
			(stroke
				(width 0.1)
				(type default)
			)
			(layer "B.Fab")
		)
		(fp_line
			(start 1.6764 0.8382)
			(end 2.1082 0.8382)
			(stroke
				(width 0.1)
				(type default)
			)
			(layer "B.Fab")
		)
		(fp_line
			(start 1.6764 -0.8382)
			(end 1.6764 -0.889)
			(stroke
				(width 0.1)
				(type default)
			)
			(layer "B.Fab")
		)
		(fp_line
			(start 1.6764 -0.889)
			(end 1.6764 -0.9398)
			(stroke
				(width 0.1)
				(type default)
			)
			(layer "B.Fab")
		)
		(fp_line
			(start 1.6764 -0.9398)
			(end -1.6764 -0.9398)
			(stroke
				(width 0.1)
				(type default)
			)
			(layer "B.Fab")
		)
		(fp_line
			(start -1.6764 0.9398)
			(end 1.6764 0.9398)
			(stroke
				(width 0.1)
				(type default)
			)
			(layer "B.Fab")
		)
		(fp_line
			(start -1.6764 0.889)
			(end -1.6764 0.9398)
			(stroke
				(width 0.1)
				(type default)
			)
			(layer "B.Fab")
		)
		(fp_line
			(start -1.6764 0.8382)
			(end -1.6764 0.889)
			(stroke
				(width 0.1)
				(type default)
			)
			(layer "B.Fab")
		)
		(fp_line
			(start -1.6764 -0.8382)
			(end -2.1082 -0.8382)
			(stroke
				(width 0.1)
				(type default)
			)
			(layer "B.Fab")
		)
		(fp_line
			(start -1.6764 -0.889)
			(end -1.6764 -0.8382)
			(stroke
				(width 0.1)
				(type default)
			)
			(layer "B.Fab")
		)
		(fp_line
			(start -1.6764 -0.9398)
			(end -1.6764 -0.889)
			(stroke
				(width 0.1)
				(type default)
			)
			(layer "B.Fab")
		)
		(fp_line
			(start -2.1082 0.8382)
			(end -1.6764 0.8382)
			(stroke
				(width 0.1)
				(type default)
			)
			(layer "B.Fab")
		)
		(fp_line
			(start -2.1082 -0.8382)
			(end -2.1082 0.8382)
			(stroke
				(width 0.1)
				(type default)
			)
			(layer "B.Fab")
		)
		(pad "1" smd rect
			(at 1.4732 0 180)
			(size 1.1684 1.5748)
			(layers "B.Cu" "B.Mask" "B.Paste")
			(net "P52V_2")
		)
		(pad "2" smd rect
			(at -1.4732 0 180)
			(size 1.1684 1.5748)
			(layers "B.Cu" "B.Mask" "B.Paste")
			(net "GND1_FIELD_SIGNAL")
		)
	)
	(footprint ""
		(layer "B.Cu")
		(at 426.593 -37.973 180)
		(property "Reference" "R5939"
			(at 0 0 0)
			(layer "B.SilkS")
			(hide yes)
			(effects
				(font
					(size 1.27 1.27)
				)
				(justify mirror)
			)
		)
		(property "Value" ""
			(at 0 0 0)
			(layer "B.Fab")
			(effects
				(font
					(size 1.27 1.27)
				)
				(justify mirror)
			)
		)
		(duplicate_pad_numbers_are_jumpers no)
		(fp_line
			(start 0.7874 0.4064)
			(end 0.7874 -0.4064)
			(stroke
				(width 0.1524)
				(type default)
			)
			(layer "B.SilkS")
		)
		(fp_line
			(start 0.7874 -0.4064)
			(end -0.7874 -0.4064)
			(stroke
				(width 0.1524)
				(type default)
			)
			(layer "B.SilkS")
		)
		(fp_line
			(start -0.7874 0.4064)
			(end 0.7874 0.4064)
			(stroke
				(width 0.1524)
				(type default)
			)
			(layer "B.SilkS")
		)
		(fp_line
			(start -0.7874 -0.4064)
			(end -0.7874 0.4064)
			(stroke
				(width 0.1524)
				(type default)
			)
			(layer "B.SilkS")
		)
		(fp_line
			(start 0.67945 0.3048)
			(end 0.67945 -0.305054)
			(stroke
				(width 0.1)
				(type default)
			)
			(layer "B.Fab")
		)
		(fp_line
			(start 0.67945 -0.305054)
			(end 0.12065 -0.305054)
			(stroke
				(width 0.1)
				(type default)
			)
			(layer "B.Fab")
		)
		(fp_line
			(start 0.12065 0.3048)
			(end 0.67945 0.3048)
			(stroke
				(width 0.1)
				(type default)
			)
			(layer "B.Fab")
		)
		(fp_line
			(start 0.12065 0.2794)
			(end 0.12065 0.3048)
			(stroke
				(width 0.1)
				(type default)
			)
			(layer "B.Fab")
		)
		(fp_line
			(start 0.12065 -0.2794)
			(end -0.12065 -0.2794)
			(stroke
				(width 0.1)
				(type default)
			)
			(layer "B.Fab")
		)
		(fp_line
			(start 0.12065 -0.305054)
			(end 0.12065 -0.2794)
			(stroke
				(width 0.1)
				(type default)
			)
			(layer "B.Fab")
		)
		(fp_line
			(start -0.120396 0.3048)
			(end -0.120396 0.2794)
			(stroke
				(width 0.1)
				(type default)
			)
			(layer "B.Fab")
		)
		(fp_line
			(start -0.120396 0.2794)
			(end 0.12065 0.2794)
			(stroke
				(width 0.1)
				(type default)
			)
			(layer "B.Fab")
		)
		(fp_line
			(start -0.12065 -0.2794)
			(end -0.12065 -0.3048)
			(stroke
				(width 0.1)
				(type default)
			)
			(layer "B.Fab")
		)
		(fp_line
			(start -0.12065 -0.3048)
			(end -0.67945 -0.3048)
			(stroke
				(width 0.1)
				(type default)
			)
			(layer "B.Fab")
		)
		(fp_line
			(start -0.67945 0.3048)
			(end -0.120396 0.3048)
			(stroke
				(width 0.1)
				(type default)
			)
			(layer "B.Fab")
		)
		(fp_line
			(start -0.67945 -0.3048)
			(end -0.67945 0.3048)
			(stroke
				(width 0.1)
				(type default)
			)
			(layer "B.Fab")
		)
		(pad "1" smd circle
			(at 0.40005 0)
			(size 0 0)
			(layers "B.Cu" "B.Mask" "B.Paste")
			(net "PCA9555_2_A0")
		)
		(pad "2" smd circle
			(at -0.40005 0)
			(size 0 0)
			(layers "B.Cu" "B.Mask" "B.Paste")
			(net "GND")
		)
	)
	(footprint ""
		(layer "B.Cu")
		(at 162.860736 -74.549 180)
		(property "Reference" "PC603"
			(at 0 0 0)
			(layer "B.SilkS")
			(hide yes)
			(effects
				(font
					(size 1.27 1.27)
				)
				(justify mirror)
			)
		)
		(property "Value" ""
			(at 0 0 0)
			(layer "B.Fab")
			(effects
				(font
					(size 1.27 1.27)
				)
				(justify mirror)
			)
		)
		(duplicate_pad_numbers_are_jumpers no)
		(fp_line
			(start 0.7874 0.4064)
			(end 0.7874 -0.4064)
			(stroke
				(width 0.1524)
				(type default)
			)
			(layer "B.SilkS")
		)
		(fp_line
			(start 0.7874 -0.4064)
			(end -0.7874 -0.4064)
			(stroke
				(width 0.1524)
				(type default)
			)
			(layer "B.SilkS")
		)
		(fp_line
			(start -0.7874 0.4064)
			(end 0.7874 0.4064)
			(stroke
				(width 0.1524)
				(type default)
			)
			(layer "B.SilkS")
		)
		(fp_line
			(start -0.7874 -0.4064)
			(end -0.7874 0.4064)
			(stroke
				(width 0.1524)
				(type default)
			)
			(layer "B.SilkS")
		)
		(fp_line
			(start 0.67945 0.3048)
			(end 0.67945 -0.305054)
			(stroke
				(width 0.1)
				(type default)
			)
			(layer "B.Fab")
		)
		(fp_line
			(start 0.67945 -0.305054)
			(end 0.12065 -0.305054)
			(stroke
				(width 0.1)
				(type default)
			)
			(layer "B.Fab")
		)
		(fp_line
			(start 0.12065 0.3048)
			(end 0.67945 0.3048)
			(stroke
				(width 0.1)
				(type default)
			)
			(layer "B.Fab")
		)
		(fp_line
			(start 0.12065 0.2794)
			(end 0.12065 0.3048)
			(stroke
				(width 0.1)
				(type default)
			)
			(layer "B.Fab")
		)
		(fp_line
			(start 0.12065 -0.2794)
			(end -0.12065 -0.2794)
			(stroke
				(width 0.1)
				(type default)
			)
			(layer "B.Fab")
		)
		(fp_line
			(start 0.12065 -0.305054)
			(end 0.12065 -0.2794)
			(stroke
				(width 0.1)
				(type default)
			)
			(layer "B.Fab")
		)
		(fp_line
			(start -0.120396 0.3048)
			(end -0.120396 0.2794)
			(stroke
				(width 0.1)
				(type default)
			)
			(layer "B.Fab")
		)
		(fp_line
			(start -0.120396 0.2794)
			(end 0.12065 0.2794)
			(stroke
				(width 0.1)
				(type default)
			)
			(layer "B.Fab")
		)
		(fp_line
			(start -0.12065 -0.2794)
			(end -0.12065 -0.3048)
			(stroke
				(width 0.1)
				(type default)
			)
			(layer "B.Fab")
		)
		(fp_line
			(start -0.12065 -0.3048)
			(end -0.67945 -0.3048)
			(stroke
				(width 0.1)
				(type default)
			)
			(layer "B.Fab")
		)
		(fp_line
			(start -0.67945 0.3048)
			(end -0.120396 0.3048)
			(stroke
				(width 0.1)
				(type default)
			)
			(layer "B.Fab")
		)
		(fp_line
			(start -0.67945 -0.3048)
			(end -0.67945 0.3048)
			(stroke
				(width 0.1)
				(type default)
			)
			(layer "B.Fab")
		)
		(pad "1" smd circle
			(at 0.40005 0)
			(size 0 0)
			(layers "B.Cu" "B.Mask" "B.Paste")
			(net "P52V_HS2_TMR")
		)
		(pad "2" smd circle
			(at -0.40005 0)
			(size 0 0)
			(layers "B.Cu" "B.Mask" "B.Paste")
			(net "GND1_FIELD_SIGNAL")
		)
	)
	(footprint ""
		(layer "B.Cu")
		(at 272.3134 -59.817 -90)
		(property "Reference" "R148"
			(at 0 0 90)
			(layer "B.SilkS")
			(hide yes)
			(effects
				(font
					(size 1.27 1.27)
				)
				(justify mirror)
			)
		)
		(property "Value" ""
			(at 0 0 90)
			(layer "B.Fab")
			(effects
				(font
					(size 1.27 1.27)
				)
				(justify mirror)
			)
		)
		(duplicate_pad_numbers_are_jumpers no)
		(fp_line
			(start -1.651 0.8382)
			(end 1.651 0.8382)
			(stroke
				(width 0.1524)
				(type default)
			)
			(layer "B.SilkS")
		)
		(fp_line
			(start 1.651 0.8382)
			(end 1.651 -0.8382)
			(stroke
				(width 0.1524)
				(type default)
			)
			(layer "B.SilkS")
		)
		(fp_line
			(start -1.651 -0.8382)
			(end -1.651 0.8382)
			(stroke
				(width 0.1524)
				(type default)
			)
			(layer "B.SilkS")
		)
		(fp_line
			(start 1.651 -0.8382)
			(end -1.651 -0.8382)
			(stroke
				(width 0.1524)
				(type default)
			)
			(layer "B.SilkS")
		)
		(fp_line
			(start -1.560576 0.7366)
			(end -1.560576 -0.7366)
			(stroke
				(width 0.1)
				(type default)
			)
			(layer "B.Fab")
		)
		(fp_line
			(start -1.524 0.7366)
			(end -1.560576 0.7366)
			(stroke
				(width 0.1)
				(type default)
			)
			(layer "B.Fab")
		)
		(fp_line
			(start 1.524 0.7366)
			(end -1.524 0.7366)
			(stroke
				(width 0.1)
				(type default)
			)
			(layer "B.Fab")
		)
		(fp_line
			(start 1.559814 0.7366)
			(end 1.524 0.7366)
			(stroke
				(width 0.1)
				(type default)
			)
			(layer "B.Fab")
		)
		(fp_line
			(start -1.560576 -0.7366)
			(end -1.524 -0.7366)
			(stroke
				(width 0.1)
				(type default)
			)
			(layer "B.Fab")
		)
		(fp_line
			(start -1.524 -0.7366)
			(end 1.524 -0.7366)
			(stroke
				(width 0.1)
				(type default)
			)
			(layer "B.Fab")
		)
		(fp_line
			(start 1.524 -0.7366)
			(end 1.559814 -0.7366)
			(stroke
				(width 0.1)
				(type default)
			)
			(layer "B.Fab")
		)
		(fp_line
			(start 1.559814 -0.7366)
			(end 1.559814 0.7366)
			(stroke
				(width 0.1)
				(type default)
			)
			(layer "B.Fab")
		)
		(pad "1" smd rect
			(at 0.94996 0 270)
			(size 1.1176 1.3716)
			(layers "B.Cu" "B.Mask" "B.Paste")
			(net "P52V_HS1")
		)
		(pad "2" smd rect
			(at -0.94996 0 270)
			(size 1.1176 1.3716)
			(layers "B.Cu" "B.Mask" "B.Paste")
			(net "PWRGD_P52V_HS1_PG")
		)
	)
	(footprint ""
		(layer "B.Cu")
		(at 179.4764 -58.039 -90)
		(property "Reference" "PR7020"
			(at 0 0 90)
			(layer "B.SilkS")
			(hide yes)
			(effects
				(font
					(size 1.27 1.27)
				)
				(justify mirror)
			)
		)
		(property "Value" ""
			(at 0 0 90)
			(layer "B.Fab")
			(effects
				(font
					(size 1.27 1.27)
				)
				(justify mirror)
			)
		)
		(duplicate_pad_numbers_are_jumpers no)
		(fp_line
			(start -2.234946 0.9271)
			(end 2.234946 0.9271)
			(stroke
				(width 0.1524)
				(type default)
			)
			(layer "B.SilkS")
		)
		(fp_line
			(start 2.234946 0.9271)
			(end 2.234946 -0.9271)
			(stroke
				(width 0.1524)
				(type default)
			)
			(layer "B.SilkS")
		)
		(fp_line
			(start -2.234946 -0.9271)
			(end -2.234946 0.9271)
			(stroke
				(width 0.1524)
				(type default)
			)
			(layer "B.SilkS")
		)
		(fp_line
			(start 2.234946 -0.9271)
			(end -2.234946 -0.9271)
			(stroke
				(width 0.1524)
				(type default)
			)
			(layer "B.SilkS")
		)
		(fp_line
			(start -1.575054 0.824992)
			(end -1.575054 -0.824992)
			(stroke
				(width 0.1)
				(type default)
			)
			(layer "B.Fab")
		)
		(fp_line
			(start 1.575054 0.824992)
			(end -1.575054 0.824992)
			(stroke
				(width 0.1)
				(type default)
			)
			(layer "B.Fab")
		)
		(fp_line
			(start -1.575054 -0.824992)
			(end 1.575054 -0.824992)
			(stroke
				(width 0.1)
				(type default)
			)
			(layer "B.Fab")
		)
		(fp_line
			(start 1.575054 -0.824992)
			(end 1.575054 0.824992)
			(stroke
				(width 0.1)
				(type default)
			)
			(layer "B.Fab")
		)
		(pad "1" smd rect
			(at 1.599946 0 90)
			(size 1.016 1.6002)
			(layers "B.Cu" "B.Mask" "B.Paste")
			(net "P52V_2")
		)
		(pad "2" smd rect
			(at -1.599946 0 90)
			(size 1.016 1.6002)
			(layers "B.Cu" "B.Mask" "B.Paste")
			(net "P52V_HS2_VCC")
		)
	)
)
